# TIMECARD (Time Appliance Project (Time Card)) — schematic netlist excerpt (pin names and nets, part order shuffled) for the footprints in the layout excerpt that follows; sources: Cadence DE-HDL packaged netlist, KiCad conversion of R4006-B0001-02_R01.brd

C189  CAPACITOR  0.1UF 25V 10%  pkg SMC_0402R_H022  page 30 : \1\ = XP1R8V_VIN ; \2\ = SG
SP27  SOLDER_PREFORM  pkg 0201_SOLDER_PREFORM_4MIL  page 34 : \1\ = NC ; \2\ = NC
C254  CAPACITOR  0.1UF 10V 10%  pkg SMC_0402R_H022  page 15 : \1\ = OSC_125M_CLKN ; \2\ = MHZ125CLKN_CLKIN

(kicad_pcb
	(version 20260206)
	(generator "pcbnew")
	(generator_version "10.0")
	(general
		(thickness 1.6)
		(legacy_teardrops no)
	)
	(paper "A4")
	(title_block
		(title "timecard-production-celestica-r4006 — R4006-B0001-02_R01.brd")
		(comment 1 "Time Appliance Project (Time Card) / footprints 367-369 of 1113")
	)
	(layers
		(0 "F.Cu" signal "TOP")
		(4 "In1.Cu" signal "L02_GND1")
		(6 "In2.Cu" signal "L03_SIG1")
		(8 "In3.Cu" signal "L04_GND2")
		(10 "In4.Cu" signal "L05_VCC1")
		(12 "In5.Cu" signal "L06_VCC2")
		(14 "In6.Cu" signal "L07_GND3")
		(16 "In7.Cu" signal "L08_SIG2")
		(18 "In8.Cu" signal "L09_GND4")
		(2 "B.Cu" signal "BOTTOM")
		(9 "F.Adhes" user "F.Adhesive")
		(11 "B.Adhes" user "B.Adhesive")
		(13 "F.Paste" user "Package Geometry/Pastemask Top")
		(15 "B.Paste" user "Package Geometry/Pastemask Bottom")
		(5 "F.SilkS" user "Ref Des/Silkscreen Top")
		(7 "B.SilkS" user "Ref Des/Silkscreen Bottom")
		(1 "F.Mask" user "Board Geometry/Soldermask Top")
		(3 "B.Mask" user "Board Geometry/Soldermask Bottom")
		(17 "Dwgs.User" user "User.Drawings")
		(19 "Cmts.User" user "User.Comments")
		(21 "Eco1.User" user "User.Eco1")
		(23 "Eco2.User" user "User.Eco2")
		(25 "Edge.Cuts" user "Board Geometry/Outline")
		(27 "Margin" user)
		(31 "F.CrtYd" user "Package Geometry/Place Bound Top")
		(29 "B.CrtYd" user "Package Geometry/Place Bound Bottom")
		(35 "F.Fab" user "Ref Des/Assembly Top")
		(33 "B.Fab" user "Ref Des/Assembly Bottom")
	)
	(footprint ""
		(layer "F.Cu")
		(at 128.6002 -65.9638)
		(property "Reference" "C189"
			(at 0.508 5.75437 0)
			(unlocked yes)
			(layer "F.SilkS")
			(effects
				(font
					(size 0.7874 0.5842)
					(thickness 0.1524)
				)
			)
		)
		(property "Value" "VAL*"
			(at 0.0762 2.067306 0)
			(unlocked yes)
			(layer "F.Fab")
			(hide yes)
			(effects
				(font
					(size 0.7874 0.5842)
					(thickness 0.1524)
				)
			)
		)
		(property "Tolerance" "TOL*"
			(at 0.0762 3.032506 0)
			(unlocked yes)
			(layer "Cmts.User")
			(hide yes)
			(effects
				(font
					(size 0.7874 0.5842)
					(thickness 0.1524)
				)
			)
		)
		(property "User Part Number" "PARTNUM*"
			(at 0.1016 4.023106 0)
			(unlocked yes)
			(layer "Cmts.User")
			(hide yes)
			(effects
				(font
					(size 0.7874 0.5842)
					(thickness 0.1524)
				)
			)
		)
		(property "Device Type" "CAPACITOR-G105-0B104-EK,0.1UF,A"
			(at 0.0508 1.127506 0)
			(unlocked yes)
			(layer "F.Fab")
			(hide yes)
			(effects
				(font
					(size 0.7874 0.5842)
					(thickness 0.1524)
				)
			)
		)
		(duplicate_pad_numbers_are_jumpers no)
		(fp_line
			(start -1.143 -0.5588)
			(end -1.143 0.5588)
			(stroke
				(width 0.1)
				(type default)
			)
			(layer "F.SilkS")
		)
		(fp_line
			(start -1.143 0.5588)
			(end 1.143 0.5588)
			(stroke
				(width 0.1)
				(type default)
			)
			(layer "F.SilkS")
		)
		(fp_line
			(start 1.143 -0.5588)
			(end -1.143 -0.5588)
			(stroke
				(width 0.1)
				(type default)
			)
			(layer "F.SilkS")
		)
		(fp_line
			(start 1.143 0.5588)
			(end 1.143 -0.5588)
			(stroke
				(width 0.1)
				(type default)
			)
			(layer "F.SilkS")
		)
		(fp_rect
			(start 1.143 -0.5588)
			(end -1.143 0.5588)
			(stroke
				(width 0)
				(type default)
			)
			(fill no)
			(layer "F.CrtYd")
		)
		(fp_line
			(start -0.508 -0.3048)
			(end -0.508 0.3048)
			(stroke
				(width 0.1)
				(type default)
			)
			(layer "F.Fab")
		)
		(fp_line
			(start -0.508 0.3048)
			(end 0.508 0.3048)
			(stroke
				(width 0.1)
				(type default)
			)
			(layer "F.Fab")
		)
		(fp_line
			(start 0.508 -0.3048)
			(end -0.508 -0.3048)
			(stroke
				(width 0.1)
				(type default)
			)
			(layer "F.Fab")
		)
		(fp_line
			(start 0.508 0.3048)
			(end 0.508 -0.3048)
			(stroke
				(width 0.1)
				(type default)
			)
			(layer "F.Fab")
		)
		(pad "1" smd rect
			(at -0.5334 0)
			(size 0.7112 0.6096)
			(layers "F.Cu" "F.Mask" "F.Paste")
			(net "XP1R8V_VIN")
		)
		(pad "2" smd rect
			(at 0.5334 0)
			(size 0.7112 0.6096)
			(layers "F.Cu" "F.Mask" "F.Paste")
			(net "SG")
		)
		(zone
			(layer "F.Cu")
			(hatch none 0.5)
			(connect_pads
				(clearance 0)
			)
			(min_thickness 0.25)
			(keepout
				(tracks allowed)
				(vias not_allowed)
				(pads allowed)
				(copperpour not_allowed)
				(footprints allowed)
			)
			(placement
				(enabled no)
				(sheetname "")
			)
			(fill
				(thermal_gap 0.5)
				(thermal_bridge_width 0.5)
				(island_removal_mode 0)
			)
			(polygon
				(pts
					(xy 128.6764 -66.2686) (xy 128.524 -66.2686) (xy 128.524 -65.659) (xy 128.6764 -65.659)
				)
			)
		)
	)
	(footprint ""
		(layer "F.Cu")
		(at 101.854 -26.67 90)
		(property "Reference" "C254"
			(at 0.508 -2.11963 90)
			(unlocked yes)
			(layer "F.SilkS")
			(effects
				(font
					(size 0.7874 0.5842)
					(thickness 0.1524)
				)
			)
		)
		(property "Value" "VAL*"
			(at 0.0762 2.067306 90)
			(unlocked yes)
			(layer "F.Fab")
			(hide yes)
			(effects
				(font
					(size 0.7874 0.5842)
					(thickness 0.1524)
				)
			)
		)
		(property "Tolerance" "TOL*"
			(at 0.0762 3.032506 90)
			(unlocked yes)
			(layer "Cmts.User")
			(hide yes)
			(effects
				(font
					(size 0.7874 0.5842)
					(thickness 0.1524)
				)
			)
		)
		(property "User Part Number" "PARTNUM*"
			(at 0.1016 4.023106 90)
			(unlocked yes)
			(layer "Cmts.User")
			(hide yes)
			(effects
				(font
					(size 0.7874 0.5842)
					(thickness 0.1524)
				)
			)
		)
		(property "Device Type" "CAPACITOR-G105-0B104-CK,0.1UF,A"
			(at 0.0508 1.127506 90)
			(unlocked yes)
			(layer "F.Fab")
			(hide yes)
			(effects
				(font
					(size 0.7874 0.5842)
					(thickness 0.1524)
				)
			)
		)
		(duplicate_pad_numbers_are_jumpers no)
		(fp_line
			(start 1.143 -0.5588)
			(end -1.143 -0.5588)
			(stroke
				(width 0.1)
				(type default)
			)
			(layer "F.SilkS")
		)
		(fp_line
			(start -1.143 -0.5588)
			(end -1.143 0.5588)
			(stroke
				(width 0.1)
				(type default)
			)
			(layer "F.SilkS")
		)
		(fp_line
			(start 1.143 0.5588)
			(end 1.143 -0.5588)
			(stroke
				(width 0.1)
				(type default)
			)
			(layer "F.SilkS")
		)
		(fp_line
			(start -1.143 0.5588)
			(end 1.143 0.5588)
			(stroke
				(width 0.1)
				(type default)
			)
			(layer "F.SilkS")
		)
		(fp_rect
			(start -1.143 -0.5588)
			(end 1.143 0.5588)
			(stroke
				(width 0)
				(type default)
			)
			(fill no)
			(layer "F.CrtYd")
		)
		(fp_line
			(start 0.508 -0.3048)
			(end -0.508 -0.3048)
			(stroke
				(width 0.1)
				(type default)
			)
			(layer "F.Fab")
		)
		(fp_line
			(start -0.508 -0.3048)
			(end -0.508 0.3048)
			(stroke
				(width 0.1)
				(type default)
			)
			(layer "F.Fab")
		)
		(fp_line
			(start 0.508 0.3048)
			(end 0.508 -0.3048)
			(stroke
				(width 0.1)
				(type default)
			)
			(layer "F.Fab")
		)
		(fp_line
			(start -0.508 0.3048)
			(end 0.508 0.3048)
			(stroke
				(width 0.1)
				(type default)
			)
			(layer "F.Fab")
		)
		(pad "1" smd rect
			(at -0.5334 0 90)
			(size 0.7112 0.6096)
			(layers "F.Cu" "F.Mask" "F.Paste")
			(net "OSC_125M_CLKN")
		)
		(pad "2" smd rect
			(at 0.5334 0 90)
			(size 0.7112 0.6096)
			(layers "F.Cu" "F.Mask" "F.Paste")
			(net "MHZ125CLKN_CLKIN")
		)
		(zone
			(layer "F.Cu")
			(hatch none 0.5)
			(connect_pads
				(clearance 0)
			)
			(min_thickness 0.25)
			(keepout
				(tracks allowed)
				(vias not_allowed)
				(pads allowed)
				(copperpour not_allowed)
				(footprints allowed)
			)
			(placement
				(enabled no)
				(sheetname "")
			)
			(fill
				(thermal_gap 0.5)
				(thermal_bridge_width 0.5)
				(island_removal_mode 0)
			)
			(polygon
				(pts
					(xy 101.5492 -26.5938) (xy 102.1588 -26.5938) (xy 102.1588 -26.7462) (xy 101.5492 -26.7462)
				)
			)
		)
	)
	(footprint ""
		(layer "F.Cu")
		(at 52.451 -131.064)
		(property "Reference" "SP27"
			(at 0 0 0)
			(layer "F.SilkS")
			(hide yes)
			(effects
				(font
					(size 1.27 1.27)
				)
			)
		)
		(property "Value" ""
			(at 0 0 0)
			(layer "F.Fab")
			(effects
				(font
					(size 1.27 1.27)
				)
			)
		)
		(duplicate_pad_numbers_are_jumpers no)
	)
)
